(kicad_pcb
	(version 20241229)
	(generator "pcbnew")
	(generator_version "9.0")
	(general
		(thickness 1.552)
		(legacy_teardrops no)
	)
	(paper "A4")
	(title_block
		(date "2023-07-25")
		(rev "1.1.4")
		(comment 9 "footprints 248-252 of 379")
	)
	(layers
		(0 "F.Cu" signal)
		(4 "In1.Cu" signal)
		(6 "In2.Cu" signal)
		(8 "In3.Cu" signal)
		(10 "In4.Cu" signal)
		(12 "In5.Cu" signal)
		(14 "In6.Cu" signal)
		(2 "B.Cu" signal)
		(9 "F.Adhes" user "F.Adhesive")
		(11 "B.Adhes" user "B.Adhesive")
		(13 "F.Paste" user)
		(15 "B.Paste" user)
		(5 "F.SilkS" user "F.Silkscreen")
		(7 "B.SilkS" user "B.Silkscreen")
		(1 "F.Mask" user)
		(3 "B.Mask" user)
		(17 "Dwgs.User" user "User.Drawings")
		(19 "Cmts.User" user "User.Comments")
		(21 "Eco1.User" user "User.Eco1")
		(23 "Eco2.User" user "User.Eco2")
		(25 "Edge.Cuts" user)
		(27 "Margin" user)
		(31 "F.CrtYd" user "F.Courtyard")
		(29 "B.CrtYd" user "B.Courtyard")
		(35 "F.Fab" user)
		(33 "B.Fab" user)
	)
	(footprint "antmicro-footprints:C_0201"
		(layer "B.Cu")
		(at 127.48 92.99 45)
		(descr "Capacitor SMD 0201")
		(tags "capacitor SMD 0201")
		(property "Reference" "C100"
			(at 1.227351 -14.874512 45)
			(layer "B.SilkS")
			(effects
				(font
					(size 0.65 0.65)
					(thickness 0.15)
				)
				(justify right bottom mirror)
			)
		)
		(property "Value" "C_100n_0201"
			(at 0 -1.399999 45)
			(layer "B.Fab")
			(hide yes)
			(effects
				(font
					(size 0.7 0.7)
					(thickness 0.15)
				)
				(justify right bottom mirror)
			)
		)
		(property "Datasheet" "https://www.yageo.com/en/Chart/Download/pdf/CC0201KRX6S5BB104"
			(at 0 0 45)
			(layer "F.Fab")
			(hide yes)
			(effects
				(font
					(size 1.27 1.27)
					(thickness 0.15)
				)
			)
		)
		(property "Description" "SMD Multilayer Ceramic Capacitor, 0.1 µF, 6.3 V, 0201 [0603 Metric], ± 10%, X6S, CC Series"
			(at 0 0 45)
			(layer "F.Fab")
			(hide yes)
			(effects
				(font
					(size 1.27 1.27)
					(thickness 0.15)
				)
			)
		)
		(property "Author" "Antmicro"
			(at 103.091887 -62.905832 0)
			(layer "B.Fab")
			(hide yes)
			(effects
				(font
					(size 1 1)
					(thickness 0.15)
				)
				(justify mirror)
			)
		)
		(property "Dielectric" ""
			(at 103.091887 -62.905832 0)
			(layer "B.Fab")
			(hide yes)
			(effects
				(font
					(size 1 1)
					(thickness 0.15)
				)
				(justify mirror)
			)
		)
		(property "License" "Apache-2.0"
			(at 103.091887 -62.905832 0)
			(layer "B.Fab")
			(hide yes)
			(effects
				(font
					(size 1 1)
					(thickness 0.15)
				)
				(justify mirror)
			)
		)
		(property "MPN" "CC0201KRX6S5BB104"
			(at 103.091887 -62.905832 0)
			(layer "B.Fab")
			(hide yes)
			(effects
				(font
					(size 1 1)
					(thickness 0.15)
				)
				(justify mirror)
			)
		)
		(property "Manufacturer" "YAGEO"
			(at 103.091887 -62.905832 0)
			(layer "B.Fab")
			(hide yes)
			(effects
				(font
					(size 1 1)
					(thickness 0.15)
				)
				(justify mirror)
			)
		)
		(property "Val" "100n"
			(at 103.091887 -62.905832 0)
			(layer "B.Fab")
			(hide yes)
			(effects
				(font
					(size 1 1)
					(thickness 0.15)
				)
				(justify mirror)
			)
		)
		(property "Voltage" ""
			(at 103.091887 -62.905832 0)
			(layer "B.Fab")
			(hide yes)
			(effects
				(font
					(size 1 1)
					(thickness 0.15)
				)
				(justify mirror)
			)
		)
		(property "Public" "False"
			(at 0 0 45)
			(unlocked yes)
			(layer "B.Fab")
			(hide yes)
			(effects
				(font
					(size 1 1)
					(thickness 0.15)
				)
				(justify mirror)
			)
		)
		(sheetname "/FPGA Power/")
		(sheetfile "FPGA_Power.kicad_sch")
		(attr smd)
		(fp_poly
			(pts
				(xy -0.7 0.35) (xy 0.7 0.35) (xy 0.7 -0.35) (xy -0.7 -0.35)
			)
			(stroke
				(width 0.05)
				(type default)
			)
			(fill no)
			(layer "B.CrtYd")
		)
		(fp_poly
			(pts
				(xy 0.3 -0.15) (xy -0.301 -0.15) (xy -0.301 0.149) (xy 0.3 0.149)
			)
			(stroke
				(width 0.15)
				(type solid)
			)
			(fill no)
			(layer "B.Fab")
		)
		(fp_text user "License: Apache-2.0"
			(at -0.72 -4.4 225)
			(layer "B.Fab")
			(effects
				(font
					(size 0.7 0.7)
					(thickness 0.15)
				)
				(justify left bottom mirror)
			)
		)
		(fp_text user "${REFERENCE}"
			(at -0.72 -3.4 225)
			(layer "B.Fab")
			(effects
				(font
					(size 0.7 0.7)
					(thickness 0.15)
				)
				(justify left bottom mirror)
			)
		)
		(fp_text user "Author: Antmicro"
			(at -0.72 -5.400001 225)
			(layer "B.Fab")
			(effects
				(font
					(size 0.7 0.7)
					(thickness 0.15)
				)
				(justify left bottom mirror)
			)
		)
		(pad "" smd roundrect
			(at -0.349 0.002 45)
			(size 0.318 0.36)
			(layers "B.Paste")
			(roundrect_rratio 0.25)
		)
		(pad "" smd roundrect
			(at 0.341 0.002 45)
			(size 0.318 0.36)
			(layers "B.Paste")
			(roundrect_rratio 0.25)
		)
		(pad "1" smd roundrect
			(at -0.321 0.002 45)
			(size 0.46 0.4)
			(layers "B.Cu" "B.Mask")
			(roundrect_rratio 0.25)
			(net 1 "GND")
			(pintype "passive")
		)
		(pad "2" smd roundrect
			(at 0.32 0.002 45)
			(size 0.46 0.4)
			(layers "B.Cu" "B.Mask")
			(roundrect_rratio 0.25)
			(net 10 "/FPGA Power/VCC_AUXA")
			(pintype "passive")
		)
	)
	(footprint "antmicro-footprints:TP_SMD_0.75mm"
		(layer "B.Cu")
		(at 102.19 88.95 90)
		(property "Reference" "TP34"
			(at -0.59 0.44 90)
			(layer "B.SilkS")
			(effects
				(font
					(size 0.65 0.65)
					(thickness 0.15)
				)
				(justify left bottom mirror)
			)
		)
		(property "Value" "TP_0.75mm_SMD"
			(at 0 -1.2 90)
			(layer "B.Fab")
			(hide yes)
			(effects
				(font
					(size 0.7 0.7)
					(thickness 0.15)
				)
				(justify right bottom mirror)
			)
		)
		(property "Description" "SMT test point"
			(at 0 0 90)
			(layer "F.Fab")
			(hide yes)
			(effects
				(font
					(size 1.27 1.27)
					(thickness 0.15)
				)
			)
		)
		(property "Author" "Antmicro"
			(at 191.14 -13.24 0)
			(layer "B.Fab")
			(hide yes)
			(effects
				(font
					(size 1 1)
					(thickness 0.15)
				)
				(justify mirror)
			)
		)
		(property "License" "Apache-2.0"
			(at 191.14 -13.24 0)
			(layer "B.Fab")
			(hide yes)
			(effects
				(font
					(size 1 1)
					(thickness 0.15)
				)
				(justify mirror)
			)
		)
		(property "MPN" ""
			(at 191.14 -13.24 0)
			(layer "B.Fab")
			(hide yes)
			(effects
				(font
					(size 1 1)
					(thickness 0.15)
				)
				(justify mirror)
			)
		)
		(property "Manufacturer" ""
			(at 191.14 -13.24 0)
			(layer "B.Fab")
			(hide yes)
			(effects
				(font
					(size 1 1)
					(thickness 0.15)
				)
				(justify mirror)
			)
		)
		(sheetname "/SDI/")
		(sheetfile "sdi.kicad_sch")
		(attr exclude_from_pos_files)
		(fp_circle
			(center 0 0)
			(end 0.475 0)
			(stroke
				(width 0.05)
				(type default)
			)
			(fill no)
			(layer "B.CrtYd")
		)
		(fp_text user "License: Apache-2.0"
			(at -0.4 -5.101 270)
			(layer "B.Fab")
			(effects
				(font
					(size 0.7 0.7)
					(thickness 0.15)
				)
				(justify left bottom mirror)
			)
		)
		(fp_text user "Author: Antmicro"
			(at -0.4 -3.901 270)
			(layer "B.Fab")
			(effects
				(font
					(size 0.7 0.7)
					(thickness 0.15)
				)
				(justify left bottom mirror)
			)
		)
		(fp_text user "${REFERENCE}"
			(at -0.4 -2.7 270)
			(layer "B.Fab")
			(effects
				(font
					(size 0.7 0.7)
					(thickness 0.15)
				)
				(justify left bottom mirror)
			)
		)
		(pad "1" smd circle
			(at 0 0 90)
			(size 0.75 0.75)
			(layers "B.Cu" "B.Mask")
			(net 208 "/SDI/JTAG{slash}~{HOST}")
			(pinfunction "1")
			(pintype "passive")
		)
	)
	(footprint "antmicro-footprints:C_0402_1005Metric"
		(layer "B.Cu")
		(at 91.62 72.96 90)
		(descr "Capacitor SMD 0402")
		(tags "capacitor SMD 0402")
		(property "Reference" "C55"
			(at 3.02 0.81 270)
			(layer "B.SilkS")
			(effects
				(font
					(size 0.65 0.65)
					(thickness 0.15)
				)
				(justify left bottom mirror)
			)
		)
		(property "Value" "C_47n_0402"
			(at 0 -1.4 270)
			(layer "B.Fab")
			(hide yes)
			(effects
				(font
					(size 0.7 0.7)
					(thickness 0.15)
				)
				(justify left bottom mirror)
			)
		)
		(property "Datasheet" "https://www.murata.com/en-us/products/productdetail?partno=GRM155R61C473KA01%23"
			(at 0 0 90)
			(layer "F.Fab")
			(hide yes)
			(effects
				(font
					(size 1.27 1.27)
					(thickness 0.15)
				)
			)
		)
		(property "Description" "SMD Multilayer Ceramic Capacitor, 47000 pF, 16 V, 0402 [1005 Metric], ± 10%, X5R, MC"
			(at 0 0 90)
			(layer "F.Fab")
			(hide yes)
			(effects
				(font
					(size 1.27 1.27)
					(thickness 0.15)
				)
			)
		)
		(property "Author" "Antmicro"
			(at 164.58 -18.66 0)
			(layer "B.Fab")
			(hide yes)
			(effects
				(font
					(size 1 1)
					(thickness 0.15)
				)
				(justify mirror)
			)
		)
		(property "Dielectric" ""
			(at 164.58 -18.66 0)
			(layer "B.Fab")
			(hide yes)
			(effects
				(font
					(size 1 1)
					(thickness 0.15)
				)
				(justify mirror)
			)
		)
		(property "License" "Apache-2.0"
			(at 164.58 -18.66 0)
			(layer "B.Fab")
			(hide yes)
			(effects
				(font
					(size 1 1)
					(thickness 0.15)
				)
				(justify mirror)
			)
		)
		(property "MPN" "GRM155R61C473KA01D"
			(at 164.58 -18.66 0)
			(layer "B.Fab")
			(hide yes)
			(effects
				(font
					(size 1 1)
					(thickness 0.15)
				)
				(justify mirror)
			)
		)
		(property "Manufacturer" "Murata"
			(at 164.58 -18.66 0)
			(layer "B.Fab")
			(hide yes)
			(effects
				(font
					(size 1 1)
					(thickness 0.15)
				)
				(justify mirror)
			)
		)
		(property "Val" "47n"
			(at 164.58 -18.66 0)
			(layer "B.Fab")
			(hide yes)
			(effects
				(font
					(size 1 1)
					(thickness 0.15)
				)
				(justify mirror)
			)
		)
		(property "Voltage" ""
			(at 164.58 -18.66 0)
			(layer "B.Fab")
			(hide yes)
			(effects
				(font
					(size 1 1)
					(thickness 0.15)
				)
				(justify mirror)
			)
		)
		(sheetname "/SDI/")
		(sheetfile "sdi.kicad_sch")
		(attr smd)
		(fp_rect
			(start -0.925 0.47)
			(end 0.925 -0.47)
			(stroke
				(width 0.05)
				(type default)
			)
			(fill no)
			(layer "B.CrtYd")
		)
		(fp_line
			(start 0.504 -0.248)
			(end -0.494 -0.248)
			(stroke
				(width 0.15)
				(type solid)
			)
			(layer "B.Fab")
		)
		(fp_line
			(start -0.494 -0.248)
			(end -0.494 0.25)
			(stroke
				(width 0.15)
				(type solid)
			)
			(layer "B.Fab")
		)
		(fp_line
			(start 0.504 0.25)
			(end 0.504 -0.248)
			(stroke
				(width 0.15)
				(type solid)
			)
			(layer "B.Fab")
		)
		(fp_line
			(start -0.494 0.25)
			(end 0.504 0.25)
			(stroke
				(width 0.15)
				(type solid)
			)
			(layer "B.Fab")
		)
		(fp_text user "License: Apache-2.0"
			(at -0.939 -5.799 270)
			(layer "B.Fab")
			(effects
				(font
					(size 0.7 0.7)
					(thickness 0.15)
				)
				(justify left bottom mirror)
			)
		)
		(fp_text user "Author: Antmicro"
			(at -0.939 -3.399 270)
			(layer "B.Fab")
			(effects
				(font
					(size 0.7 0.7)
					(thickness 0.15)
				)
				(justify left bottom mirror)
			)
		)
		(fp_text user "${REFERENCE}"
			(at -0.939 -4.599 270)
			(layer "B.Fab")
			(effects
				(font
					(size 0.7 0.7)
					(thickness 0.15)
				)
				(justify left bottom mirror)
			)
		)
		(pad "1" smd roundrect
			(at -0.48 0 90)
			(size 0.59 0.64)
			(layers "B.Cu" "B.Mask" "B.Paste")
			(roundrect_rratio 0.25)
			(net 156 "Net-(U15B-LF)")
			(pintype "passive")
		)
		(pad "2" smd roundrect
			(at 0.48 0 90)
			(size 0.59 0.64)
			(layers "B.Cu" "B.Mask" "B.Paste")
			(roundrect_rratio 0.25)
			(net 1 "GND")
			(pintype "passive")
		)
	)
	(footprint "antmicro-footprints:TP_SMD_0.75mm"
		(layer "B.Cu")
		(at 91.6392 88.95 90)
		(property "Reference" "TP40"
			(at -2.99 0.2908 90)
			(layer "B.SilkS")
			(effects
				(font
					(size 0.65 0.65)
					(thickness 0.15)
				)
				(justify right bottom mirror)
			)
		)
		(property "Value" "TP_0.75mm_SMD"
			(at 0 -1.2 90)
			(layer "B.Fab")
			(hide yes)
			(effects
				(font
					(size 0.7 0.7)
					(thickness 0.15)
				)
				(justify right bottom mirror)
			)
		)
		(property "Description" "SMT test point"
			(at 0 0 90)
			(layer "F.Fab")
			(hide yes)
			(effects
				(font
					(size 1.27 1.27)
					(thickness 0.15)
				)
			)
		)
		(property "Author" "Antmicro"
			(at 180.5892 -2.6892 0)
			(layer "B.Fab")
			(hide yes)
			(effects
				(font
					(size 1 1)
					(thickness 0.15)
				)
				(justify mirror)
			)
		)
		(property "License" "Apache-2.0"
			(at 180.5892 -2.6892 0)
			(layer "B.Fab")
			(hide yes)
			(effects
				(font
					(size 1 1)
					(thickness 0.15)
				)
				(justify mirror)
			)
		)
		(property "MPN" ""
			(at 180.5892 -2.6892 0)
			(layer "B.Fab")
			(hide yes)
			(effects
				(font
					(size 1 1)
					(thickness 0.15)
				)
				(justify mirror)
			)
		)
		(property "Manufacturer" ""
			(at 180.5892 -2.6892 0)
			(layer "B.Fab")
			(hide yes)
			(effects
				(font
					(size 1 1)
					(thickness 0.15)
				)
				(justify mirror)
			)
		)
		(sheetname "/SDI/")
		(sheetfile "sdi.kicad_sch")
		(attr exclude_from_pos_files)
		(fp_circle
			(center 0 0)
			(end 0.475 0)
			(stroke
				(width 0.05)
				(type default)
			)
			(fill no)
			(layer "B.CrtYd")
		)
		(fp_text user "${REFERENCE}"
			(at -0.4 -2.7 270)
			(layer "B.Fab")
			(effects
				(font
					(size 0.7 0.7)
					(thickness 0.15)
				)
				(justify left bottom mirror)
			)
		)
		(fp_text user "Author: Antmicro"
			(at -0.4 -3.901 270)
			(layer "B.Fab")
			(effects
				(font
					(size 0.7 0.7)
					(thickness 0.15)
				)
				(justify left bottom mirror)
			)
		)
		(fp_text user "License: Apache-2.0"
			(at -0.4 -5.101 270)
			(layer "B.Fab")
			(effects
				(font
					(size 0.7 0.7)
					(thickness 0.15)
				)
				(justify left bottom mirror)
			)
		)
		(pad "1" smd circle
			(at 0 0 90)
			(size 0.75 0.75)
			(layers "B.Cu" "B.Mask")
			(net 176 "/SDI/STANDBY")
			(pinfunction "1")
			(pintype "passive")
		)
	)
	(footprint "antmicro-footprints:C_0603_1608Metric"
		(layer "B.Cu")
		(at 134.78 91.12)
		(descr "Capacitor SMD 0603")
		(tags "capacitor 0603")
		(property "Reference" "C88"
			(at -1 -0.98 0)
			(layer "B.SilkS")
			(effects
				(font
					(size 0.65 0.65)
					(thickness 0.15)
				)
				(justify right bottom mirror)
			)
		)
		(property "Value" "C_10u_0603"
			(at 0 -1.6 0)
			(layer "B.Fab")
			(hide yes)
			(effects
				(font
					(size 0.7 0.7)
					(thickness 0.15)
				)
				(justify right bottom mirror)
			)
		)
		(property "Datasheet" "https://www.murata.com/products/productdetail?partno=GRM188R61A106KE69%23"
			(at 0 0 0)
			(layer "F.Fab")
			(hide yes)
			(effects
				(font
					(size 1.27 1.27)
					(thickness 0.15)
				)
			)
		)
		(property "Description" "SMD Multilayer Ceramic Capacitor, 10 µF, 10 V, 0603 [1608 Metric], ± 10%, X5R, GRM Series"
			(at 0 0 0)
			(layer "F.Fab")
			(hide yes)
			(effects
				(font
					(size 1.27 1.27)
					(thickness 0.15)
				)
			)
		)
		(property "Author" "Antmicro"
			(at 0 0 0)
			(layer "B.Fab")
			(hide yes)
			(effects
				(font
					(size 1 1)
					(thickness 0.15)
				)
				(justify mirror)
			)
		)
		(property "License" "Apache-2.0"
			(at 0 0 0)
			(layer "B.Fab")
			(hide yes)
			(effects
				(font
					(size 1 1)
					(thickness 0.15)
				)
				(justify mirror)
			)
		)
		(property "MPN" "GRM188R61A106KE69D"
			(at 0 0 0)
			(layer "B.Fab")
			(hide yes)
			(effects
				(font
					(size 1 1)
					(thickness 0.15)
				)
				(justify mirror)
			)
		)
		(property "Manufacturer" "Murata"
			(at 0 0 0)
			(layer "B.Fab")
			(hide yes)
			(effects
				(font
					(size 1 1)
					(thickness 0.15)
				)
				(justify mirror)
			)
		)
		(property "Val" "10u"
			(at 0 0 0)
			(layer "B.Fab")
			(hide yes)
			(effects
				(font
					(size 1 1)
					(thickness 0.15)
				)
				(justify mirror)
			)
		)
		(property "Voltage" ""
			(at 0 0 0)
			(layer "B.Fab")
			(hide yes)
			(effects
				(font
					(size 1 1)
					(thickness 0.15)
				)
				(justify mirror)
			)
		)
		(property "Dielectric" "template_dielectric"
			(at 0 0 0)
			(unlocked yes)
			(layer "B.Fab")
			(hide yes)
			(effects
				(font
					(size 1 1)
					(thickness 0.15)
				)
				(justify mirror)
			)
		)
		(sheetname "/FPGA Power/")
		(sheetfile "FPGA_Power.kicad_sch")
		(attr smd)
		(fp_line
			(start -0.15 -0.4)
			(end 0.15 -0.4)
			(stroke
				(width 0.15)
				(type solid)
			)
			(layer "B.SilkS")
		)
		(fp_line
			(start -0.15 0.4)
			(end 0.15 0.4)
			(stroke
				(width 0.15)
				(type solid)
			)
			(layer "B.SilkS")
		)
		(fp_rect
			(start -1.25 0.65)
			(end 1.25 -0.65)
			(stroke
				(width 0.05)
				(type solid)
			)
			(fill no)
			(layer "B.CrtYd")
		)
		(fp_rect
			(start -0.8 0.4)
			(end 0.8 -0.4)
			(stroke
				(width 0.15)
				(type solid)
			)
			(fill no)
			(layer "B.Fab")
		)
		(fp_text user "${REFERENCE}"
			(at -1.682 -3.895 180)
			(layer "B.Fab")
			(effects
				(font
					(size 0.7 0.7)
					(thickness 0.15)
				)
				(justify left bottom mirror)
			)
		)
		(fp_text user "Author: Antmicro"
			(at -1.682 -4.894 180)
			(layer "B.Fab")
			(effects
				(font
					(size 0.7 0.7)
					(thickness 0.15)
				)
				(justify left bottom mirror)
			)
		)
		(fp_text user "License: Apache-2.0"
			(at -1.682 -5.895 180)
			(layer "B.Fab")
			(effects
				(font
					(size 0.7 0.7)
					(thickness 0.15)
				)
				(justify left bottom mirror)
			)
		)
		(pad "1" smd roundrect
			(at -0.7 0)
			(size 0.8 1)
			(layers "B.Cu" "B.Mask" "B.Paste")
			(roundrect_rratio 0.2)
			(net 1 "GND")
			(pintype "passive")
		)
		(pad "2" smd roundrect
			(at 0.7 0)
			(size 0.8 1)
			(layers "B.Cu" "B.Mask" "B.Paste")
			(roundrect_rratio 0.2)
			(net 10 "/FPGA Power/VCC_AUXA")
			(pintype "passive")
		)
	)
)
